# TIMECARD (Time Appliance Project (Time Card)) — schematic netlist excerpt (pin names and nets, part order shuffled) for the footprints in the layout excerpt that follows; sources: Cadence DE-HDL packaged netlist, KiCad conversion of R4006-B0001-02_R01.brd

C98  CAPACITOR  4.7UF 6.3V 20%  pkg SMC_0402R_H026  page 24 : \1\ = XP3R3V_VPLL ; \2\ = SG
R218  RESISTOR  100OHM 1%  pkg SMC_0402R_H016  page 10 : \1\ = FPGA_M1 ; \2\ = SG

(kicad_pcb
	(version 20260206)
	(generator "pcbnew")
	(generator_version "10.0")
	(general
		(thickness 1.6)
		(legacy_teardrops no)
	)
	(paper "A4")
	(title_block
		(title "timecard-production-celestica-r4006 — R4006-B0001-02_R01.brd")
		(comment 1 "Time Appliance Project (Time Card) / footprints 689-690 of 1113")
	)
	(layers
		(0 "F.Cu" signal "TOP")
		(4 "In1.Cu" signal "L02_GND1")
		(6 "In2.Cu" signal "L03_SIG1")
		(8 "In3.Cu" signal "L04_GND2")
		(10 "In4.Cu" signal "L05_VCC1")
		(12 "In5.Cu" signal "L06_VCC2")
		(14 "In6.Cu" signal "L07_GND3")
		(16 "In7.Cu" signal "L08_SIG2")
		(18 "In8.Cu" signal "L09_GND4")
		(2 "B.Cu" signal "BOTTOM")
		(9 "F.Adhes" user "F.Adhesive")
		(11 "B.Adhes" user "B.Adhesive")
		(13 "F.Paste" user "Package Geometry/Pastemask Top")
		(15 "B.Paste" user "Package Geometry/Pastemask Bottom")
		(5 "F.SilkS" user "Ref Des/Silkscreen Top")
		(7 "B.SilkS" user "Ref Des/Silkscreen Bottom")
		(1 "F.Mask" user "Board Geometry/Soldermask Top")
		(3 "B.Mask" user "Board Geometry/Soldermask Bottom")
		(17 "Dwgs.User" user "User.Drawings")
		(19 "Cmts.User" user "User.Comments")
		(21 "Eco1.User" user "User.Eco1")
		(23 "Eco2.User" user "User.Eco2")
		(25 "Edge.Cuts" user "Board Geometry/Outline")
		(27 "Margin" user)
		(31 "F.CrtYd" user "Package Geometry/Place Bound Top")
		(29 "B.CrtYd" user "Package Geometry/Place Bound Bottom")
		(35 "F.Fab" user "Ref Des/Assembly Top")
		(33 "B.Fab" user "Ref Des/Assembly Bottom")
	)
	(footprint ""
		(layer "B.Cu")
		(at 27.559 -91.059 -90)
		(property "Reference" "C98"
			(at -2.794 -0.21463 270)
			(unlocked yes)
			(layer "B.SilkS")
			(effects
				(font
					(size 0.7874 0.5842)
					(thickness 0.1524)
				)
				(justify mirror)
			)
		)
		(property "Value" "VAL*"
			(at -0.02032 2.13233 270)
			(unlocked yes)
			(layer "B.Fab")
			(hide yes)
			(effects
				(font
					(size 0.7874 0.5842)
					(thickness 0.1524)
				)
				(justify mirror)
			)
		)
		(property "Tolerance" "TOL*"
			(at -0.044704 3.05435 270)
			(unlocked yes)
			(layer "Cmts.User")
			(hide yes)
			(effects
				(font
					(size 0.7874 0.5842)
					(thickness 0.1524)
				)
				(justify mirror)
			)
		)
		(property "User Part Number" "PARTNUM*"
			(at -0.02032 4.024884 270)
			(unlocked yes)
			(layer "Cmts.User")
			(hide yes)
			(effects
				(font
					(size 0.7874 0.5842)
					(thickness 0.1524)
				)
				(justify mirror)
			)
		)
		(property "Device Type" "CAPACITOR-G105-0F475-BM,4.7UF,A"
			(at -0.008382 1.210564 270)
			(unlocked yes)
			(layer "B.Fab")
			(hide yes)
			(effects
				(font
					(size 0.7874 0.5842)
					(thickness 0.1524)
				)
				(justify mirror)
			)
		)
		(duplicate_pad_numbers_are_jumpers no)
		(fp_line
			(start -1.143 0.5588)
			(end -1.143 -0.5588)
			(stroke
				(width 0.1)
				(type default)
			)
			(layer "B.SilkS")
		)
		(fp_line
			(start 1.143 0.5588)
			(end -1.143 0.5588)
			(stroke
				(width 0.1)
				(type default)
			)
			(layer "B.SilkS")
		)
		(fp_line
			(start -1.143 -0.5588)
			(end 1.143 -0.5588)
			(stroke
				(width 0.1)
				(type default)
			)
			(layer "B.SilkS")
		)
		(fp_line
			(start 1.143 -0.5588)
			(end 1.143 0.5588)
			(stroke
				(width 0.1)
				(type default)
			)
			(layer "B.SilkS")
		)
		(fp_poly
			(pts
				(xy 1.143 0.5588) (xy -1.143 0.5588) (xy -1.143 -0.5588) (xy 1.143 -0.5588)
			)
			(stroke
				(width 0)
				(type default)
			)
			(fill no)
			(layer "B.CrtYd")
		)
		(fp_line
			(start -0.508 0.3048)
			(end -0.508 -0.3048)
			(stroke
				(width 0.1)
				(type default)
			)
			(layer "B.Fab")
		)
		(fp_line
			(start 0.508 0.3048)
			(end -0.508 0.3048)
			(stroke
				(width 0.1)
				(type default)
			)
			(layer "B.Fab")
		)
		(fp_line
			(start -0.508 -0.3048)
			(end 0.508 -0.3048)
			(stroke
				(width 0.1)
				(type default)
			)
			(layer "B.Fab")
		)
		(fp_line
			(start 0.508 -0.3048)
			(end 0.508 0.3048)
			(stroke
				(width 0.1)
				(type default)
			)
			(layer "B.Fab")
		)
		(pad "1" smd rect
			(at 0.5334 0 90)
			(size 0.7112 0.6096)
			(layers "B.Cu" "B.Mask" "B.Paste")
			(net "XP3R3V_VPLL")
		)
		(pad "2" smd rect
			(at -0.5334 0 90)
			(size 0.7112 0.6096)
			(layers "B.Cu" "B.Mask" "B.Paste")
			(net "SG")
		)
		(zone
			(layer "B.Cu")
			(hatch none 0.5)
			(connect_pads
				(clearance 0)
			)
			(min_thickness 0.25)
			(keepout
				(tracks allowed)
				(vias not_allowed)
				(pads allowed)
				(copperpour not_allowed)
				(footprints allowed)
			)
			(placement
				(enabled no)
				(sheetname "")
			)
			(fill
				(thermal_gap 0.5)
				(thermal_bridge_width 0.5)
				(island_removal_mode 0)
			)
			(polygon
				(pts
					(xy 27.2542 -90.9828) (xy 27.8638 -90.9828) (xy 27.8638 -91.1352) (xy 27.2542 -91.1352)
				)
			)
		)
		(zone
			(layer "B.Cu")
			(hatch none 0.5)
			(connect_pads
				(clearance 0)
			)
			(min_thickness 0.25)
			(keepout
				(tracks not_allowed)
				(vias allowed)
				(pads allowed)
				(copperpour not_allowed)
				(footprints allowed)
			)
			(placement
				(enabled no)
				(sheetname "")
			)
			(fill
				(thermal_gap 0.5)
				(thermal_bridge_width 0.5)
				(island_removal_mode 0)
			)
			(polygon
				(pts
					(xy 27.2542 -90.9828) (xy 27.8638 -90.9828) (xy 27.8638 -91.1352) (xy 27.2542 -91.1352)
				)
			)
		)
	)
	(footprint ""
		(layer "B.Cu")
		(at 124.587 -42.545 180)
		(property "Reference" "R218"
			(at -3.429 -0.16637 0)
			(unlocked yes)
			(layer "B.SilkS")
			(effects
				(font
					(size 0.7874 0.5842)
					(thickness 0.1524)
				)
				(justify mirror)
			)
		)
		(property "Value" "VAL*"
			(at -0.02032 2.13233 180)
			(unlocked yes)
			(layer "B.Fab")
			(hide yes)
			(effects
				(font
					(size 0.7874 0.5842)
					(thickness 0.1524)
				)
				(justify mirror)
			)
		)
		(property "Tolerance" "TOL*"
			(at -0.044704 3.05435 180)
			(unlocked yes)
			(layer "Cmts.User")
			(hide yes)
			(effects
				(font
					(size 0.7874 0.5842)
					(thickness 0.1524)
				)
				(justify mirror)
			)
		)
		(property "User Part Number" "PARTNUM*"
			(at -0.02032 4.024884 180)
			(unlocked yes)
			(layer "Cmts.User")
			(hide yes)
			(effects
				(font
					(size 0.7874 0.5842)
					(thickness 0.1524)
				)
				(justify mirror)
			)
		)
		(property "Device Type" "RESISTOR-G155-11000-01,100OHM,A"
			(at -0.008382 1.210564 180)
			(unlocked yes)
			(layer "B.Fab")
			(hide yes)
			(effects
				(font
					(size 0.7874 0.5842)
					(thickness 0.1524)
				)
				(justify mirror)
			)
		)
		(duplicate_pad_numbers_are_jumpers no)
		(fp_line
			(start 1.143 0.5588)
			(end -1.143 0.5588)
			(stroke
				(width 0.1)
				(type default)
			)
			(layer "B.SilkS")
		)
		(fp_line
			(start 1.143 -0.5588)
			(end 1.143 0.5588)
			(stroke
				(width 0.1)
				(type default)
			)
			(layer "B.SilkS")
		)
		(fp_line
			(start -1.143 0.5588)
			(end -1.143 -0.5588)
			(stroke
				(width 0.1)
				(type default)
			)
			(layer "B.SilkS")
		)
		(fp_line
			(start -1.143 -0.5588)
			(end 1.143 -0.5588)
			(stroke
				(width 0.1)
				(type default)
			)
			(layer "B.SilkS")
		)
		(fp_rect
			(start 1.143 0.5588)
			(end -1.143 -0.5588)
			(stroke
				(width 0)
				(type default)
			)
			(fill no)
			(layer "B.CrtYd")
		)
		(fp_line
			(start 0.508 0.3048)
			(end -0.508 0.3048)
			(stroke
				(width 0.1)
				(type default)
			)
			(layer "B.Fab")
		)
		(fp_line
			(start 0.508 -0.3048)
			(end 0.508 0.3048)
			(stroke
				(width 0.1)
				(type default)
			)
			(layer "B.Fab")
		)
		(fp_line
			(start -0.508 0.3048)
			(end -0.508 -0.3048)
			(stroke
				(width 0.1)
				(type default)
			)
			(layer "B.Fab")
		)
		(fp_line
			(start -0.508 -0.3048)
			(end 0.508 -0.3048)
			(stroke
				(width 0.1)
				(type default)
			)
			(layer "B.Fab")
		)
		(pad "1" smd rect
			(at 0.5334 0)
			(size 0.7112 0.6096)
			(layers "B.Cu" "B.Mask" "B.Paste")
			(net "FPGA_M1")
		)
		(pad "2" smd rect
			(at -0.5334 0)
			(size 0.7112 0.6096)
			(layers "B.Cu" "B.Mask" "B.Paste")
			(net "SG")
		)
		(zone
			(layer "B.Cu")
			(hatch none 0.5)
			(connect_pads
				(clearance 0)
			)
			(min_thickness 0.25)
			(keepout
				(tracks allowed)
				(vias not_allowed)
				(pads allowed)
				(copperpour not_allowed)
				(footprints allowed)
			)
			(placement
				(enabled no)
				(sheetname "")
			)
			(fill
				(thermal_gap 0.5)
				(thermal_bridge_width 0.5)
				(island_removal_mode 0)
			)
			(polygon
				(pts
					(xy 124.5108 -42.8498) (xy 124.5108 -42.2402) (xy 124.6632 -42.2402) (xy 124.6632 -42.8498)
				)
			)
		)
	)
)
